# T6G (Grand Teton) — schematic netlist excerpt (pin names and nets, part order shuffled) for the footprints in the layout excerpt that follows; sources: Cadence DE-HDL packaged netlist, KiCad conversion of 04192023_DAF0TMB3IC0_F0TG_MB_C_brd_V02_OCP.brd

R765  Q_RES  15.4K 1% CHIP  pkg 0402LF  page 93 : A = PD_CHH_CPU0_DIMM_SAA ; B = GND
C3901  Q_CAP  22UF 4V 20% X6S  pkg C0402  page 72 : A = PVDDCR_SOC_P1 ; B = GND
PC184_3  Q_CAP  22UF 16V 20% X6S  pkg C0805  page 206 : A = SW_P12V_AUX_PVDDIO_P0_FLT ; B = GND

(kicad_pcb
	(version 20260206)
	(generator "pcbnew")
	(generator_version "10.0")
	(general
		(thickness 1.6)
		(legacy_teardrops no)
	)
	(paper "A4")
	(title_block
		(title "04192023_DAF0TMB3IC0_F0TG_MB_C_brd_V02_OCP.brd")
		(comment 1 "Grand Teton / footprints 6033-6035 of 8354")
	)
	(layers
		(0 "F.Cu" signal "TOP")
		(4 "In1.Cu" signal "GND")
		(6 "In2.Cu" signal "IN1")
		(8 "In3.Cu" signal "GND1")
		(10 "In4.Cu" signal "IN2")
		(12 "In5.Cu" signal "GND2")
		(14 "In6.Cu" signal "IN3")
		(16 "In7.Cu" signal "GND3")
		(18 "In8.Cu" signal "VCC")
		(20 "In9.Cu" signal "VCC1")
		(22 "In10.Cu" signal "GND4")
		(24 "In11.Cu" signal "IN4")
		(26 "In12.Cu" signal "GND5")
		(28 "In13.Cu" signal "IN5")
		(30 "In14.Cu" signal "GND6")
		(32 "In15.Cu" signal "IN6")
		(34 "In16.Cu" signal "GND7")
		(2 "B.Cu" signal "BOTTOM")
		(9 "F.Adhes" user "F.Adhesive")
		(11 "B.Adhes" user "B.Adhesive")
		(13 "F.Paste" user "Package Geometry/Pastemask Top")
		(15 "B.Paste" user "Package Geometry/Pastemask Bottom")
		(5 "F.SilkS" user "Ref Des/Silkscreen Top")
		(7 "B.SilkS" user "Ref Des/Silkscreen Bottom")
		(1 "F.Mask" user "Board Geometry/Soldermask Top")
		(3 "B.Mask" user "Board Geometry/Soldermask Bottom")
		(17 "Dwgs.User" user "User.Drawings")
		(19 "Cmts.User" user "User.Comments")
		(21 "Eco1.User" user "User.Eco1")
		(23 "Eco2.User" user "User.Eco2")
		(25 "Edge.Cuts" user "Board Geometry/Outline")
		(27 "Margin" user)
		(31 "F.CrtYd" user "Package Geometry/Place Bound Top")
		(29 "B.CrtYd" user "Package Geometry/Place Bound Bottom")
		(35 "F.Fab" user "Ref Des/Assembly Top")
		(33 "B.Fab" user "Ref Des/Assembly Bottom")
	)
	(footprint ""
		(layer "B.Cu")
		(at 112.425988 -256.012442 -90)
		(property "Reference" "C3901"
			(at 0 0 90)
			(layer "B.SilkS")
			(hide yes)
			(effects
				(font
					(size 1.27 1.27)
				)
				(justify mirror)
			)
		)
		(property "Value" ""
			(at 0 0 90)
			(layer "B.Fab")
			(effects
				(font
					(size 1.27 1.27)
				)
				(justify mirror)
			)
		)
		(duplicate_pad_numbers_are_jumpers no)
		(fp_line
			(start -0.7874 0.4064)
			(end 0.7874 0.4064)
			(stroke
				(width 0.1524)
				(type default)
			)
			(layer "B.SilkS")
		)
		(fp_line
			(start 0.7874 0.4064)
			(end 0.7874 -0.4064)
			(stroke
				(width 0.1524)
				(type default)
			)
			(layer "B.SilkS")
		)
		(fp_line
			(start -0.7874 -0.4064)
			(end -0.7874 0.4064)
			(stroke
				(width 0.1524)
				(type default)
			)
			(layer "B.SilkS")
		)
		(fp_line
			(start 0.7874 -0.4064)
			(end -0.7874 -0.4064)
			(stroke
				(width 0.1524)
				(type default)
			)
			(layer "B.SilkS")
		)
		(fp_line
			(start -0.67945 0.3048)
			(end -0.120396 0.3048)
			(stroke
				(width 0.1)
				(type default)
			)
			(layer "B.Fab")
		)
		(fp_line
			(start -0.120396 0.3048)
			(end -0.120396 0.2794)
			(stroke
				(width 0.1)
				(type default)
			)
			(layer "B.Fab")
		)
		(fp_line
			(start 0.12065 0.3048)
			(end 0.67945 0.3048)
			(stroke
				(width 0.1)
				(type default)
			)
			(layer "B.Fab")
		)
		(fp_line
			(start 0.67945 0.3048)
			(end 0.67945 -0.305054)
			(stroke
				(width 0.1)
				(type default)
			)
			(layer "B.Fab")
		)
		(fp_line
			(start -0.120396 0.2794)
			(end 0.12065 0.2794)
			(stroke
				(width 0.1)
				(type default)
			)
			(layer "B.Fab")
		)
		(fp_line
			(start 0.12065 0.2794)
			(end 0.12065 0.3048)
			(stroke
				(width 0.1)
				(type default)
			)
			(layer "B.Fab")
		)
		(fp_line
			(start -0.12065 -0.2794)
			(end -0.12065 -0.3048)
			(stroke
				(width 0.1)
				(type default)
			)
			(layer "B.Fab")
		)
		(fp_line
			(start 0.12065 -0.2794)
			(end -0.12065 -0.2794)
			(stroke
				(width 0.1)
				(type default)
			)
			(layer "B.Fab")
		)
		(fp_line
			(start -0.67945 -0.3048)
			(end -0.67945 0.3048)
			(stroke
				(width 0.1)
				(type default)
			)
			(layer "B.Fab")
		)
		(fp_line
			(start -0.12065 -0.3048)
			(end -0.67945 -0.3048)
			(stroke
				(width 0.1)
				(type default)
			)
			(layer "B.Fab")
		)
		(fp_line
			(start 0.12065 -0.305054)
			(end 0.12065 -0.2794)
			(stroke
				(width 0.1)
				(type default)
			)
			(layer "B.Fab")
		)
		(fp_line
			(start 0.67945 -0.305054)
			(end 0.12065 -0.305054)
			(stroke
				(width 0.1)
				(type default)
			)
			(layer "B.Fab")
		)
		(pad "1" smd circle
			(at 0.40005 0 90)
			(size 0 0)
			(layers "B.Cu" "B.Mask" "B.Paste")
			(net "PVDDCR_SOC_P1")
		)
		(pad "2" smd circle
			(at -0.40005 0 90)
			(size 0 0)
			(layers "B.Cu" "B.Mask" "B.Paste")
			(net "GND")
		)
	)
	(footprint ""
		(layer "B.Cu")
		(at 286.952182 -346.784168 90)
		(property "Reference" "PC184_3"
			(at 0 0 90)
			(layer "B.SilkS")
			(hide yes)
			(effects
				(font
					(size 1.27 1.27)
				)
				(justify mirror)
			)
		)
		(property "Value" ""
			(at 0 0 90)
			(layer "B.Fab")
			(effects
				(font
					(size 1.27 1.27)
				)
				(justify mirror)
			)
		)
		(duplicate_pad_numbers_are_jumpers no)
		(fp_line
			(start 1.524 -0.762)
			(end -1.524 -0.762)
			(stroke
				(width 0.1524)
				(type default)
			)
			(layer "B.SilkS")
		)
		(fp_line
			(start -1.524 -0.762)
			(end -1.524 0.762)
			(stroke
				(width 0.1524)
				(type default)
			)
			(layer "B.SilkS")
		)
		(fp_line
			(start 1.524 0.762)
			(end 1.524 -0.762)
			(stroke
				(width 0.1524)
				(type default)
			)
			(layer "B.SilkS")
		)
		(fp_line
			(start -1.524 0.762)
			(end 1.524 0.762)
			(stroke
				(width 0.1524)
				(type default)
			)
			(layer "B.SilkS")
		)
		(fp_line
			(start 1.1049 -0.724916)
			(end 1.1049 0.724916)
			(stroke
				(width 0.1)
				(type default)
			)
			(layer "B.Fab")
		)
		(fp_line
			(start -1.1049 -0.724916)
			(end 1.1049 -0.724916)
			(stroke
				(width 0.1)
				(type default)
			)
			(layer "B.Fab")
		)
		(fp_line
			(start 1.1049 0.724916)
			(end -1.1049 0.724916)
			(stroke
				(width 0.1)
				(type default)
			)
			(layer "B.Fab")
		)
		(fp_line
			(start -1.1049 0.724916)
			(end -1.1049 -0.724916)
			(stroke
				(width 0.1)
				(type default)
			)
			(layer "B.Fab")
		)
		(pad "1" smd rect
			(at 0.889 0 90)
			(size 1.016 1.27)
			(layers "B.Cu" "B.Mask" "B.Paste")
			(net "SW_P12V_AUX_PVDDIO_P0_FLT")
		)
		(pad "2" smd rect
			(at -0.889 0 90)
			(size 1.016 1.27)
			(layers "B.Cu" "B.Mask" "B.Paste")
			(net "GND")
		)
	)
	(footprint ""
		(layer "B.Cu")
		(at 420.667688 -194.88531 180)
		(property "Reference" "R765"
			(at 0 0 0)
			(layer "B.SilkS")
			(hide yes)
			(effects
				(font
					(size 1.27 1.27)
				)
				(justify mirror)
			)
		)
		(property "Value" ""
			(at 0 0 0)
			(layer "B.Fab")
			(effects
				(font
					(size 1.27 1.27)
				)
				(justify mirror)
			)
		)
		(duplicate_pad_numbers_are_jumpers no)
		(fp_line
			(start 0.7874 0.4064)
			(end 0.7874 -0.4064)
			(stroke
				(width 0.1524)
				(type default)
			)
			(layer "B.SilkS")
		)
		(fp_line
			(start 0.7874 -0.4064)
			(end -0.7874 -0.4064)
			(stroke
				(width 0.1524)
				(type default)
			)
			(layer "B.SilkS")
		)
		(fp_line
			(start -0.7874 0.4064)
			(end 0.7874 0.4064)
			(stroke
				(width 0.1524)
				(type default)
			)
			(layer "B.SilkS")
		)
		(fp_line
			(start -0.7874 -0.4064)
			(end -0.7874 0.4064)
			(stroke
				(width 0.1524)
				(type default)
			)
			(layer "B.SilkS")
		)
		(fp_line
			(start 0.67945 0.3048)
			(end 0.67945 -0.305054)
			(stroke
				(width 0.1)
				(type default)
			)
			(layer "B.Fab")
		)
		(fp_line
			(start 0.67945 -0.305054)
			(end 0.12065 -0.305054)
			(stroke
				(width 0.1)
				(type default)
			)
			(layer "B.Fab")
		)
		(fp_line
			(start 0.12065 0.3048)
			(end 0.67945 0.3048)
			(stroke
				(width 0.1)
				(type default)
			)
			(layer "B.Fab")
		)
		(fp_line
			(start 0.12065 0.2794)
			(end 0.12065 0.3048)
			(stroke
				(width 0.1)
				(type default)
			)
			(layer "B.Fab")
		)
		(fp_line
			(start 0.12065 -0.2794)
			(end -0.12065 -0.2794)
			(stroke
				(width 0.1)
				(type default)
			)
			(layer "B.Fab")
		)
		(fp_line
			(start 0.12065 -0.305054)
			(end 0.12065 -0.2794)
			(stroke
				(width 0.1)
				(type default)
			)
			(layer "B.Fab")
		)
		(fp_line
			(start -0.120396 0.3048)
			(end -0.120396 0.2794)
			(stroke
				(width 0.1)
				(type default)
			)
			(layer "B.Fab")
		)
		(fp_line
			(start -0.120396 0.2794)
			(end 0.12065 0.2794)
			(stroke
				(width 0.1)
				(type default)
			)
			(layer "B.Fab")
		)
		(fp_line
			(start -0.12065 -0.2794)
			(end -0.12065 -0.3048)
			(stroke
				(width 0.1)
				(type default)
			)
			(layer "B.Fab")
		)
		(fp_line
			(start -0.12065 -0.3048)
			(end -0.67945 -0.3048)
			(stroke
				(width 0.1)
				(type default)
			)
			(layer "B.Fab")
		)
		(fp_line
			(start -0.67945 0.3048)
			(end -0.120396 0.3048)
			(stroke
				(width 0.1)
				(type default)
			)
			(layer "B.Fab")
		)
		(fp_line
			(start -0.67945 -0.3048)
			(end -0.67945 0.3048)
			(stroke
				(width 0.1)
				(type default)
			)
			(layer "B.Fab")
		)
		(pad "1" smd circle
			(at 0.40005 0)
			(size 0 0)
			(layers "B.Cu" "B.Mask" "B.Paste")
			(net "PD_CHH_CPU0_DIMM_SAA")
		)
		(pad "2" smd circle
			(at -0.40005 0)
			(size 0 0)
			(layers "B.Cu" "B.Mask" "B.Paste")
			(net "GND")
		)
	)
)
